# BASEBOARD_FAB2 (Tioga Pass) — schematic netlist excerpt (pin names and nets, part order shuffled) for the footprints in the layout excerpt that follows; sources: Cadence DE-HDL packaged netlist, KiCad conversion of Wiwynn_Tioga_Pass_MB.brd

R3R14  RES  10.0 1% CHIP  pkg 0402  page 99 : A = SMB_DDR_DEF_SDA_G_R ; B = SMB_DDR_DEF_SDA_G
R25W149  RES  4.75K 1% CHIP  pkg 0402  page 150 : A = GND ; B = TP_RGMII1TXD2_GPIOT4
C8U4  CAP_A  47UF 4V 20% X5R  pkg 0603V  page 225 : A = PVDDQ_GHJ ; B = GND

(kicad_pcb
	(version 20260206)
	(generator "pcbnew")
	(generator_version "10.0")
	(general
		(thickness 1.6)
		(legacy_teardrops no)
	)
	(paper "A4")
	(title_block
		(title "Wiwynn_Tioga_Pass_MB.brd")
		(comment 1 "Tioga Pass / footprints 2348-2350 of 4770")
	)
	(layers
		(0 "F.Cu" signal "TOP")
		(4 "In1.Cu" signal "L2GND")
		(6 "In2.Cu" signal "L3")
		(8 "In3.Cu" signal "L4GND")
		(10 "In4.Cu" signal "L5")
		(12 "In5.Cu" signal "L6GND")
		(14 "In6.Cu" signal "L7VCC")
		(16 "In7.Cu" signal "L8VCC")
		(18 "In8.Cu" signal "L9GND")
		(20 "In9.Cu" signal "L10")
		(22 "In10.Cu" signal "L11GND")
		(24 "In11.Cu" signal "L12")
		(26 "In12.Cu" signal "L13GND")
		(2 "B.Cu" signal "BOTTOM")
		(9 "F.Adhes" user "F.Adhesive")
		(11 "B.Adhes" user "B.Adhesive")
		(13 "F.Paste" user "Package Geometry/Pastemask Top")
		(15 "B.Paste" user "Package Geometry/Pastemask Bottom")
		(5 "F.SilkS" user "Ref Des/Silkscreen Top")
		(7 "B.SilkS" user "Ref Des/Silkscreen Bottom")
		(1 "F.Mask" user "Board Geometry/Soldermask Top")
		(3 "B.Mask" user "Board Geometry/Soldermask Bottom")
		(17 "Dwgs.User" user "User.Drawings")
		(19 "Cmts.User" user "User.Comments")
		(21 "Eco1.User" user "User.Eco1")
		(23 "Eco2.User" user "User.Eco2")
		(25 "Edge.Cuts" user "Board Geometry/Outline")
		(27 "Margin" user)
		(31 "F.CrtYd" user "Package Geometry/Place Bound Top")
		(29 "B.CrtYd" user "Package Geometry/Place Bound Bottom")
		(35 "F.Fab" user "Ref Des/Assembly Top")
		(33 "B.Fab" user "Ref Des/Assembly Bottom")
	)
	(footprint ""
		(layer "B.Cu")
		(at 407.5176 -29.4132 180)
		(property "Reference" "R25W149"
			(at 0.8382 -0.67818 180)
			(unlocked yes)
			(layer "B.SilkS")
			(effects
				(font
					(size 0.4064 0.254)
					(thickness 0.1524)
				)
				(justify left mirror)
			)
		)
		(property "Value" ""
			(at 0 0 0)
			(layer "B.Fab")
			(effects
				(font
					(size 1.27 1.27)
				)
				(justify mirror)
			)
		)
		(duplicate_pad_numbers_are_jumpers no)
		(fp_poly
			(pts
				(xy 0.2794 -0.1016) (xy -0.2794 -0.1016) (xy -0.2794 0.9906) (xy 0.2794 0.9906)
			)
			(stroke
				(width 0)
				(type default)
			)
			(fill no)
			(layer "B.CrtYd")
		)
		(fp_line
			(start 0.2794 0.9906)
			(end -0.2794 0.9906)
			(stroke
				(width 0.1)
				(type default)
			)
			(layer "B.Fab")
		)
		(fp_line
			(start 0.2794 -0.1016)
			(end 0.2794 0.9906)
			(stroke
				(width 0.1)
				(type default)
			)
			(layer "B.Fab")
		)
		(fp_line
			(start -0.2794 0.9906)
			(end -0.2794 -0.1016)
			(stroke
				(width 0.1)
				(type default)
			)
			(layer "B.Fab")
		)
		(fp_line
			(start -0.2794 -0.1016)
			(end 0.2794 -0.1016)
			(stroke
				(width 0.1)
				(type default)
			)
			(layer "B.Fab")
		)
		(pad "1" smd rect
			(at 0 0)
			(size 0.508 0.508)
			(layers "B.Cu" "B.Mask" "B.Paste")
			(net "GND")
		)
		(pad "2" smd rect
			(at 0 0.889)
			(size 0.508 0.508)
			(layers "B.Cu" "B.Mask" "B.Paste")
			(net "TP_RGMII1TXD2_GPIOT4")
		)
		(zone
			(layer "B.Cu")
			(hatch none 0.5)
			(connect_pads
				(clearance 0)
			)
			(min_thickness 0.25)
			(keepout
				(tracks not_allowed)
				(vias allowed)
				(pads allowed)
				(copperpour not_allowed)
				(footprints allowed)
			)
			(placement
				(enabled no)
				(sheetname "")
			)
			(fill
				(thermal_gap 0.5)
				(thermal_bridge_width 0.5)
				(island_removal_mode 0)
			)
			(polygon
				(pts
					(xy 407.2636 -30.0482) (xy 407.7716 -30.0482) (xy 407.7716 -29.6672) (xy 407.2636 -29.6672)
				)
			)
		)
		(zone
			(layer "B.Cu")
			(hatch none 0.5)
			(connect_pads
				(clearance 0)
			)
			(min_thickness 0.25)
			(keepout
				(tracks allowed)
				(vias not_allowed)
				(pads allowed)
				(copperpour not_allowed)
				(footprints allowed)
			)
			(placement
				(enabled no)
				(sheetname "")
			)
			(fill
				(thermal_gap 0.5)
				(thermal_bridge_width 0.5)
				(island_removal_mode 0)
			)
			(polygon
				(pts
					(xy 407.2636 -29.6672) (xy 407.7716 -29.6672) (xy 407.7716 -30.0482) (xy 407.2636 -30.0482)
				)
			)
		)
	)
	(footprint ""
		(layer "B.Cu")
		(at 88.392 -8.1534 90)
		(property "Reference" "C8U4"
			(at -1.848866 0.752348 90)
			(unlocked yes)
			(layer "B.SilkS")
			(effects
				(font
					(size 1.27 0.9652)
					(thickness 0.1524)
				)
				(justify mirror)
			)
		)
		(property "Value" ""
			(at 0 0 90)
			(layer "B.Fab")
			(effects
				(font
					(size 1.27 1.27)
				)
				(justify mirror)
			)
		)
		(duplicate_pad_numbers_are_jumpers no)
		(fp_rect
			(start 0.500126 1.598422)
			(end -0.500126 -0.201422)
			(stroke
				(width 0)
				(type default)
			)
			(fill no)
			(layer "B.CrtYd")
		)
		(fp_line
			(start 0.500126 -0.201422)
			(end -0.500126 -0.201422)
			(stroke
				(width 0.1)
				(type default)
			)
			(layer "B.Fab")
		)
		(fp_line
			(start -0.500126 -0.201422)
			(end -0.500126 1.598422)
			(stroke
				(width 0.1)
				(type default)
			)
			(layer "B.Fab")
		)
		(fp_line
			(start 0.500126 1.598422)
			(end 0.500126 -0.201422)
			(stroke
				(width 0.1)
				(type default)
			)
			(layer "B.Fab")
		)
		(fp_line
			(start -0.500126 1.598422)
			(end 0.500126 1.598422)
			(stroke
				(width 0.1)
				(type default)
			)
			(layer "B.Fab")
		)
		(pad "1" smd rect
			(at 0 0)
			(size 0.889 0.9906)
			(layers "B.Cu" "B.Mask" "B.Paste")
			(net "PVDDQ_GHJ")
		)
		(pad "2" smd rect
			(at 0 1.397)
			(size 0.889 0.9906)
			(layers "B.Cu" "B.Mask" "B.Paste")
			(net "GND")
		)
		(zone
			(layer "B.Cu")
			(hatch none 0.5)
			(connect_pads
				(clearance 0)
			)
			(min_thickness 0.25)
			(keepout
				(tracks allowed)
				(vias not_allowed)
				(pads allowed)
				(copperpour not_allowed)
				(footprints allowed)
			)
			(placement
				(enabled no)
				(sheetname "")
			)
			(fill
				(thermal_gap 0.5)
				(thermal_bridge_width 0.5)
				(island_removal_mode 0)
			)
			(polygon
				(pts
					(xy 89.3445 -8.6487) (xy 88.8365 -8.6487) (xy 88.8365 -7.6581) (xy 89.3445 -7.6581)
				)
			)
		)
		(zone
			(layer "B.Cu")
			(hatch none 0.5)
			(connect_pads
				(clearance 0)
			)
			(min_thickness 0.25)
			(keepout
				(tracks not_allowed)
				(vias allowed)
				(pads allowed)
				(copperpour not_allowed)
				(footprints allowed)
			)
			(placement
				(enabled no)
				(sheetname "")
			)
			(fill
				(thermal_gap 0.5)
				(thermal_bridge_width 0.5)
				(island_removal_mode 0)
			)
			(polygon
				(pts
					(xy 89.3445 -8.6487) (xy 88.8365 -8.6487) (xy 88.8365 -7.6581) (xy 89.3445 -7.6581)
				)
			)
		)
	)
	(footprint ""
		(layer "B.Cu")
		(at 330.091288 -63.38824 90)
		(property "Reference" "R3R14"
			(at 0 0 90)
			(layer "B.SilkS")
			(hide yes)
			(effects
				(font
					(size 1.27 1.27)
				)
				(justify mirror)
			)
		)
		(property "Value" ""
			(at 0 0 90)
			(layer "B.Fab")
			(effects
				(font
					(size 1.27 1.27)
				)
				(justify mirror)
			)
		)
		(duplicate_pad_numbers_are_jumpers no)
		(fp_poly
			(pts
				(xy 0.2794 -0.1016) (xy -0.2794 -0.1016) (xy -0.2794 0.9906) (xy 0.2794 0.9906)
			)
			(stroke
				(width 0)
				(type default)
			)
			(fill no)
			(layer "B.CrtYd")
		)
		(fp_line
			(start 0.2794 -0.1016)
			(end 0.2794 0.9906)
			(stroke
				(width 0.1)
				(type default)
			)
			(layer "B.Fab")
		)
		(fp_line
			(start -0.2794 -0.1016)
			(end 0.2794 -0.1016)
			(stroke
				(width 0.1)
				(type default)
			)
			(layer "B.Fab")
		)
		(fp_line
			(start 0.2794 0.9906)
			(end -0.2794 0.9906)
			(stroke
				(width 0.1)
				(type default)
			)
			(layer "B.Fab")
		)
		(fp_line
			(start -0.2794 0.9906)
			(end -0.2794 -0.1016)
			(stroke
				(width 0.1)
				(type default)
			)
			(layer "B.Fab")
		)
		(pad "1" smd rect
			(at 0 0 270)
			(size 0.508 0.508)
			(layers "B.Cu" "B.Mask" "B.Paste")
			(net "SMB_DDR_DEF_SDA_G_R")
		)
		(pad "2" smd rect
			(at 0 0.889 270)
			(size 0.508 0.508)
			(layers "B.Cu" "B.Mask" "B.Paste")
			(net "SMB_DDR_DEF_SDA_G")
		)
		(zone
			(layer "B.Cu")
			(hatch none 0.5)
			(connect_pads
				(clearance 0)
			)
			(min_thickness 0.25)
			(keepout
				(tracks allowed)
				(vias not_allowed)
				(pads allowed)
				(copperpour not_allowed)
				(footprints allowed)
			)
			(placement
				(enabled no)
				(sheetname "")
			)
			(fill
				(thermal_gap 0.5)
				(thermal_bridge_width 0.5)
				(island_removal_mode 0)
			)
			(polygon
				(pts
					(xy 330.345288 -63.64224) (xy 330.345288 -63.13424) (xy 330.726288 -63.13424) (xy 330.726288 -63.64224)
				)
			)
		)
		(zone
			(layer "B.Cu")
			(hatch none 0.5)
			(connect_pads
				(clearance 0)
			)
			(min_thickness 0.25)
			(keepout
				(tracks not_allowed)
				(vias allowed)
				(pads allowed)
				(copperpour not_allowed)
				(footprints allowed)
			)
			(placement
				(enabled no)
				(sheetname "")
			)
			(fill
				(thermal_gap 0.5)
				(thermal_bridge_width 0.5)
				(island_removal_mode 0)
			)
			(polygon
				(pts
					(xy 330.726288 -63.64224) (xy 330.726288 -63.13424) (xy 330.345288 -63.13424) (xy 330.345288 -63.64224)
				)
			)
		)
	)
)
